# T6G (Grand Teton) — schematic netlist excerpt (pin names and nets, part order shuffled) for the footprints in the layout excerpt that follows; sources: Cadence DE-HDL packaged netlist, KiCad conversion of 04192023_DAF0TMB3IC0_F0TG_MB_C_brd_V02_OCP.brd

R6308  Q_RES  200K 1% EMPTY  pkg 0402LF  page 179 : A = P3V3_AUX ; B = USB_HUB2_MRP_CFG_NON_REM
R6254  Q_RES  0 5% CHIP  pkg 0402LF  page 271 : A = HSC_TYPE_ADC_A0 ; B = SMB_HSC_TYPE_ADC_SDA

(kicad_pcb
	(version 20260206)
	(generator "pcbnew")
	(generator_version "10.0")
	(general
		(thickness 1.6)
		(legacy_teardrops no)
	)
	(paper "A4")
	(title_block
		(title "04192023_DAF0TMB3IC0_F0TG_MB_C_brd_V02_OCP.brd")
		(comment 1 "Grand Teton / footprints 933-934 of 8354")
	)
	(layers
		(0 "F.Cu" signal "TOP")
		(4 "In1.Cu" signal "GND")
		(6 "In2.Cu" signal "IN1")
		(8 "In3.Cu" signal "GND1")
		(10 "In4.Cu" signal "IN2")
		(12 "In5.Cu" signal "GND2")
		(14 "In6.Cu" signal "IN3")
		(16 "In7.Cu" signal "GND3")
		(18 "In8.Cu" signal "VCC")
		(20 "In9.Cu" signal "VCC1")
		(22 "In10.Cu" signal "GND4")
		(24 "In11.Cu" signal "IN4")
		(26 "In12.Cu" signal "GND5")
		(28 "In13.Cu" signal "IN5")
		(30 "In14.Cu" signal "GND6")
		(32 "In15.Cu" signal "IN6")
		(34 "In16.Cu" signal "GND7")
		(2 "B.Cu" signal "BOTTOM")
		(9 "F.Adhes" user "F.Adhesive")
		(11 "B.Adhes" user "B.Adhesive")
		(13 "F.Paste" user "Package Geometry/Pastemask Top")
		(15 "B.Paste" user "Package Geometry/Pastemask Bottom")
		(5 "F.SilkS" user "Ref Des/Silkscreen Top")
		(7 "B.SilkS" user "Ref Des/Silkscreen Bottom")
		(1 "F.Mask" user "Board Geometry/Soldermask Top")
		(3 "B.Mask" user "Board Geometry/Soldermask Bottom")
		(17 "Dwgs.User" user "User.Drawings")
		(19 "Cmts.User" user "User.Comments")
		(21 "Eco1.User" user "User.Eco1")
		(23 "Eco2.User" user "User.Eco2")
		(25 "Edge.Cuts" user "Board Geometry/Outline")
		(27 "Margin" user)
		(31 "F.CrtYd" user "Package Geometry/Place Bound Top")
		(29 "B.CrtYd" user "Package Geometry/Place Bound Bottom")
		(35 "F.Fab" user "Ref Des/Assembly Top")
		(33 "B.Fab" user "Ref Des/Assembly Bottom")
	)
	(footprint ""
		(layer "F.Cu")
		(at 110.565946 -54.882034 -90)
		(property "Reference" "R6308"
			(at 0 0 270)
			(layer "F.SilkS")
			(hide yes)
			(effects
				(font
					(size 1.27 1.27)
				)
			)
		)
		(property "Value" ""
			(at 0 0 270)
			(layer "F.Fab")
			(effects
				(font
					(size 1.27 1.27)
				)
			)
		)
		(duplicate_pad_numbers_are_jumpers no)
		(fp_line
			(start -0.7874 0.4064)
			(end -0.7874 -0.4064)
			(stroke
				(width 0.1524)
				(type default)
			)
			(layer "F.SilkS")
		)
		(fp_line
			(start 0.7874 0.4064)
			(end -0.7874 0.4064)
			(stroke
				(width 0.1524)
				(type default)
			)
			(layer "F.SilkS")
		)
		(fp_line
			(start -0.7874 -0.4064)
			(end 0.7874 -0.4064)
			(stroke
				(width 0.1524)
				(type default)
			)
			(layer "F.SilkS")
		)
		(fp_line
			(start 0.7874 -0.4064)
			(end 0.7874 0.4064)
			(stroke
				(width 0.1524)
				(type default)
			)
			(layer "F.SilkS")
		)
		(fp_line
			(start -0.67945 0.3048)
			(end -0.67945 -0.305054)
			(stroke
				(width 0.1)
				(type default)
			)
			(layer "F.Fab")
		)
		(fp_line
			(start -0.12065 0.3048)
			(end -0.67945 0.3048)
			(stroke
				(width 0.1)
				(type default)
			)
			(layer "F.Fab")
		)
		(fp_line
			(start 0.120396 0.3048)
			(end 0.120396 0.2794)
			(stroke
				(width 0.1)
				(type default)
			)
			(layer "F.Fab")
		)
		(fp_line
			(start 0.67945 0.3048)
			(end 0.120396 0.3048)
			(stroke
				(width 0.1)
				(type default)
			)
			(layer "F.Fab")
		)
		(fp_line
			(start -0.12065 0.2794)
			(end -0.12065 0.3048)
			(stroke
				(width 0.1)
				(type default)
			)
			(layer "F.Fab")
		)
		(fp_line
			(start 0.120396 0.2794)
			(end -0.12065 0.2794)
			(stroke
				(width 0.1)
				(type default)
			)
			(layer "F.Fab")
		)
		(fp_line
			(start -0.12065 -0.2794)
			(end 0.12065 -0.2794)
			(stroke
				(width 0.1)
				(type default)
			)
			(layer "F.Fab")
		)
		(fp_line
			(start 0.12065 -0.2794)
			(end 0.12065 -0.3048)
			(stroke
				(width 0.1)
				(type default)
			)
			(layer "F.Fab")
		)
		(fp_line
			(start 0.12065 -0.3048)
			(end 0.67945 -0.3048)
			(stroke
				(width 0.1)
				(type default)
			)
			(layer "F.Fab")
		)
		(fp_line
			(start 0.67945 -0.3048)
			(end 0.67945 0.3048)
			(stroke
				(width 0.1)
				(type default)
			)
			(layer "F.Fab")
		)
		(fp_line
			(start -0.67945 -0.305054)
			(end -0.12065 -0.305054)
			(stroke
				(width 0.1)
				(type default)
			)
			(layer "F.Fab")
		)
		(fp_line
			(start -0.12065 -0.305054)
			(end -0.12065 -0.2794)
			(stroke
				(width 0.1)
				(type default)
			)
			(layer "F.Fab")
		)
		(pad "1" smd circle
			(at -0.40005 0 270)
			(size 0 0)
			(layers "F.Cu" "F.Mask" "F.Paste")
			(net "P3V3_AUX")
		)
		(pad "2" smd circle
			(at 0.40005 0 270)
			(size 0 0)
			(layers "F.Cu" "F.Mask" "F.Paste")
			(net "USB_HUB2_MRP_CFG_NON_REM")
		)
	)
	(footprint ""
		(layer "F.Cu")
		(at 427.739048 -423.606214 -90)
		(property "Reference" "R6254"
			(at 0 0 270)
			(layer "F.SilkS")
			(hide yes)
			(effects
				(font
					(size 1.27 1.27)
				)
			)
		)
		(property "Value" ""
			(at 0 0 270)
			(layer "F.Fab")
			(effects
				(font
					(size 1.27 1.27)
				)
			)
		)
		(duplicate_pad_numbers_are_jumpers no)
		(fp_line
			(start -0.7874 0.4064)
			(end -0.7874 -0.4064)
			(stroke
				(width 0.1524)
				(type default)
			)
			(layer "F.SilkS")
		)
		(fp_line
			(start 0.7874 0.4064)
			(end -0.7874 0.4064)
			(stroke
				(width 0.1524)
				(type default)
			)
			(layer "F.SilkS")
		)
		(fp_line
			(start -0.7874 -0.4064)
			(end 0.7874 -0.4064)
			(stroke
				(width 0.1524)
				(type default)
			)
			(layer "F.SilkS")
		)
		(fp_line
			(start 0.7874 -0.4064)
			(end 0.7874 0.4064)
			(stroke
				(width 0.1524)
				(type default)
			)
			(layer "F.SilkS")
		)
		(fp_line
			(start -0.67945 0.3048)
			(end -0.67945 -0.305054)
			(stroke
				(width 0.1)
				(type default)
			)
			(layer "F.Fab")
		)
		(fp_line
			(start -0.12065 0.3048)
			(end -0.67945 0.3048)
			(stroke
				(width 0.1)
				(type default)
			)
			(layer "F.Fab")
		)
		(fp_line
			(start 0.120396 0.3048)
			(end 0.120396 0.2794)
			(stroke
				(width 0.1)
				(type default)
			)
			(layer "F.Fab")
		)
		(fp_line
			(start 0.67945 0.3048)
			(end 0.120396 0.3048)
			(stroke
				(width 0.1)
				(type default)
			)
			(layer "F.Fab")
		)
		(fp_line
			(start -0.12065 0.2794)
			(end -0.12065 0.3048)
			(stroke
				(width 0.1)
				(type default)
			)
			(layer "F.Fab")
		)
		(fp_line
			(start 0.120396 0.2794)
			(end -0.12065 0.2794)
			(stroke
				(width 0.1)
				(type default)
			)
			(layer "F.Fab")
		)
		(fp_line
			(start -0.12065 -0.2794)
			(end 0.12065 -0.2794)
			(stroke
				(width 0.1)
				(type default)
			)
			(layer "F.Fab")
		)
		(fp_line
			(start 0.12065 -0.2794)
			(end 0.12065 -0.3048)
			(stroke
				(width 0.1)
				(type default)
			)
			(layer "F.Fab")
		)
		(fp_line
			(start 0.12065 -0.3048)
			(end 0.67945 -0.3048)
			(stroke
				(width 0.1)
				(type default)
			)
			(layer "F.Fab")
		)
		(fp_line
			(start 0.67945 -0.3048)
			(end 0.67945 0.3048)
			(stroke
				(width 0.1)
				(type default)
			)
			(layer "F.Fab")
		)
		(fp_line
			(start -0.67945 -0.305054)
			(end -0.12065 -0.305054)
			(stroke
				(width 0.1)
				(type default)
			)
			(layer "F.Fab")
		)
		(fp_line
			(start -0.12065 -0.305054)
			(end -0.12065 -0.2794)
			(stroke
				(width 0.1)
				(type default)
			)
			(layer "F.Fab")
		)
		(pad "1" smd circle
			(at -0.40005 0 270)
			(size 0 0)
			(layers "F.Cu" "F.Mask" "F.Paste")
			(net "HSC_TYPE_ADC_A0")
		)
		(pad "2" smd circle
			(at 0.40005 0 270)
			(size 0 0)
			(layers "F.Cu" "F.Mask" "F.Paste")
			(net "SMB_HSC_TYPE_ADC_SDA")
		)
	)
)
